(kicad_pcb
	(version 20260206)
	(generator "pcbnew")
	(generator_version "10.0")
	(general
		(thickness 1.6)
		(legacy_teardrops no)
	)
	(paper "A4")
	(title_block
		(title "panther-plus-userver — 13130-1b_20150205.brd")
		(comment 1 "Honey Badger (Wiwynn) / footprints 696-704 of 1509")
	)
	(layers
		(0 "F.Cu" signal "TOP")
		(4 "In1.Cu" signal "L2")
		(6 "In2.Cu" signal "L3")
		(8 "In3.Cu" signal "L4")
		(10 "In4.Cu" signal "L5")
		(12 "In5.Cu" signal "L6")
		(14 "In6.Cu" signal "L7")
		(16 "In7.Cu" signal "L8")
		(18 "In8.Cu" signal "L9")
		(20 "In9.Cu" signal "L10")
		(22 "In10.Cu" signal "L11")
		(2 "B.Cu" signal "BOTTOM")
		(9 "F.Adhes" user "F.Adhesive")
		(11 "B.Adhes" user "B.Adhesive")
		(13 "F.Paste" user "Package Geometry/Pastemask Top")
		(15 "B.Paste" user "Package Geometry/Pastemask Bottom")
		(5 "F.SilkS" user "Ref Des/Silkscreen Top")
		(7 "B.SilkS" user "Ref Des/Silkscreen Bottom")
		(1 "F.Mask" user "Board Geometry/Soldermask Top")
		(3 "B.Mask" user "Board Geometry/Soldermask Bottom")
		(17 "Dwgs.User" user "User.Drawings")
		(19 "Cmts.User" user "User.Comments")
		(21 "Eco1.User" user "User.Eco1")
		(23 "Eco2.User" user "User.Eco2")
		(25 "Edge.Cuts" user "Board Geometry/Outline")
		(27 "Margin" user)
		(31 "F.CrtYd" user "Package Geometry/Place Bound Top")
		(29 "B.CrtYd" user "Package Geometry/Place Bound Bottom")
		(35 "F.Fab" user "Ref Des/Assembly Top")
		(33 "B.Fab" user "Ref Des/Assembly Bottom")
	)
	(footprint ""
		(layer "F.Cu")
		(at 55.626 -45.847 -90)
		(property "Reference" "R46"
			(at 0 0 270)
			(layer "F.SilkS")
			(hide yes)
			(effects
				(font
					(size 1.27 1.27)
				)
			)
		)
		(property "Value" "10KR2F-2-GP"
			(at 0.064008 -3.993896 270)
			(unlocked yes)
			(layer "F.Fab")
			(hide yes)
			(effects
				(font
					(size 1.016 1.016)
					(thickness 0.1524)
				)
			)
		)
		(property "Device Type" "R402H16"
			(at 0.064008 -5.517896 270)
			(unlocked yes)
			(layer "F.Fab")
			(hide yes)
			(effects
				(font
					(size 1.016 1.016)
					(thickness 0.1524)
				)
			)
		)
		(duplicate_pad_numbers_are_jumpers no)
		(fp_rect
			(start -0.381 0.8382)
			(end 0.381 -0.8382)
			(stroke
				(width 0)
				(type default)
			)
			(fill no)
			(layer "F.CrtYd")
		)
		(fp_rect
			(start -0.381 0.8382)
			(end 0.381 -0.8382)
			(stroke
				(width 0)
				(type default)
			)
			(fill no)
			(layer "F.Fab")
		)
		(pad "1" smd custom
			(at 0 -0.4318 270)
			(size 0.127 0.127)
			(layers "F.Cu" "F.Mask" "F.Paste")
			(net "P12V")
			(options
				(clearance outline)
				(anchor circle)
			)
			(primitives
				(gr_poly
					(pts
						(arc
							(start -0.2032 -0.2794)
							(mid -0.239121 -0.264521)
							(end -0.254 -0.2286)
						)
						(arc
							(start -0.254 0.2286)
							(mid -0.239121 0.264521)
							(end -0.2032 0.2794)
						)
						(arc
							(start 0.2032 0.2794)
							(mid 0.239121 0.264521)
							(end 0.254 0.2286)
						)
						(arc
							(start 0.254 -0.2286)
							(mid 0.239121 -0.264521)
							(end 0.2032 -0.2794)
						)
					)
					(width 0)
					(fill yes)
				)
			)
		)
		(pad "2" smd custom
			(at 0 0.4318 270)
			(size 0.127 0.127)
			(layers "F.Cu" "F.Mask" "F.Paste")
			(net "SW_P3V3_CPU_EN_LV_D")
			(options
				(clearance outline)
				(anchor circle)
			)
			(primitives
				(gr_poly
					(pts
						(arc
							(start -0.2032 -0.2794)
							(mid -0.239121 -0.264521)
							(end -0.254 -0.2286)
						)
						(arc
							(start -0.254 0.2286)
							(mid -0.239121 0.264521)
							(end -0.2032 0.2794)
						)
						(arc
							(start 0.2032 0.2794)
							(mid 0.239121 0.264521)
							(end 0.254 0.2286)
						)
						(arc
							(start 0.254 -0.2286)
							(mid 0.239121 -0.264521)
							(end 0.2032 -0.2794)
						)
					)
					(width 0)
					(fill yes)
				)
			)
		)
	)
	(footprint ""
		(layer "F.Cu")
		(at 183.007 -14.859 180)
		(property "Reference" "PC208"
			(at 0 0 180)
			(layer "F.SilkS")
			(hide yes)
			(effects
				(font
					(size 1.27 1.27)
				)
			)
		)
		(property "Value" "SC10U6D3V3MX-GP"
			(at 0 -2.8194 180)
			(unlocked yes)
			(layer "F.Fab")
			(hide yes)
			(effects
				(font
					(size 1.016 1.016)
					(thickness 0.1524)
				)
			)
		)
		(property "Device Type" "C603H38"
			(at 0 -4.3434 180)
			(unlocked yes)
			(layer "F.Fab")
			(hide yes)
			(effects
				(font
					(size 1.016 1.016)
					(thickness 0.1524)
				)
			)
		)
		(duplicate_pad_numbers_are_jumpers no)
		(fp_line
			(start -0.4064 0)
			(end 0.4064 0)
			(stroke
				(width 0.2286)
				(type default)
			)
			(layer "F.SilkS")
		)
		(fp_rect
			(start -0.635 1.1811)
			(end 0.635 -1.1811)
			(stroke
				(width 0)
				(type default)
			)
			(fill no)
			(layer "F.CrtYd")
		)
		(fp_rect
			(start -0.635 1.1811)
			(end 0.635 -1.1811)
			(stroke
				(width 0)
				(type default)
			)
			(fill no)
			(layer "F.Fab")
		)
		(pad "1" smd custom
			(at 0 -0.6604 180)
			(size 0.19685 0.19685)
			(layers "F.Cu" "F.Mask" "F.Paste")
			(net "GND")
			(options
				(clearance outline)
				(anchor circle)
			)
			(primitives
				(gr_poly
					(pts
						(arc
							(start 0.508 -0.2921)
							(mid 0.478242 -0.363942)
							(end 0.4064 -0.3937)
						)
						(arc
							(start -0.4064 -0.3937)
							(mid -0.478242 -0.363942)
							(end -0.508 -0.2921)
						)
						(arc
							(start -0.508 0.2921)
							(mid -0.478242 0.363942)
							(end -0.4064 0.3937)
						)
						(arc
							(start 0.4064 0.3937)
							(mid 0.478242 0.363942)
							(end 0.508 0.2921)
						)
					)
					(width 0)
					(fill yes)
				)
			)
		)
		(pad "2" smd custom
			(at 0 0.6604 180)
			(size 0.19685 0.19685)
			(layers "F.Cu" "F.Mask" "F.Paste")
			(net "PV_VDDR")
			(options
				(clearance outline)
				(anchor circle)
			)
			(primitives
				(gr_poly
					(pts
						(arc
							(start 0.508 -0.2921)
							(mid 0.478242 -0.363942)
							(end 0.4064 -0.3937)
						)
						(arc
							(start -0.4064 -0.3937)
							(mid -0.478242 -0.363942)
							(end -0.508 -0.2921)
						)
						(arc
							(start -0.508 0.2921)
							(mid -0.478242 0.363942)
							(end -0.4064 0.3937)
						)
						(arc
							(start 0.4064 0.3937)
							(mid 0.478242 0.363942)
							(end 0.508 0.2921)
						)
					)
					(width 0)
					(fill yes)
				)
			)
		)
	)
	(footprint ""
		(layer "F.Cu")
		(at 128.778 -56.388)
		(property "Reference" "C106"
			(at 0 0 0)
			(layer "F.SilkS")
			(hide yes)
			(effects
				(font
					(size 1.27 1.27)
				)
			)
		)
		(property "Value" "SC10U6D3V3MX-GP"
			(at 0 -2.8194 0)
			(unlocked yes)
			(layer "F.Fab")
			(hide yes)
			(effects
				(font
					(size 1.016 1.016)
					(thickness 0.1524)
				)
			)
		)
		(property "Device Type" "C603H38"
			(at 0 -4.3434 0)
			(unlocked yes)
			(layer "F.Fab")
			(hide yes)
			(effects
				(font
					(size 1.016 1.016)
					(thickness 0.1524)
				)
			)
		)
		(duplicate_pad_numbers_are_jumpers no)
		(fp_line
			(start -0.4064 0)
			(end 0.4064 0)
			(stroke
				(width 0.2286)
				(type default)
			)
			(layer "F.SilkS")
		)
		(fp_rect
			(start -0.635 1.1811)
			(end 0.635 -1.1811)
			(stroke
				(width 0)
				(type default)
			)
			(fill no)
			(layer "F.CrtYd")
		)
		(fp_rect
			(start -0.635 1.1811)
			(end 0.635 -1.1811)
			(stroke
				(width 0)
				(type default)
			)
			(fill no)
			(layer "F.Fab")
		)
		(pad "1" smd custom
			(at 0 -0.6604)
			(size 0.19685 0.19685)
			(layers "F.Cu" "F.Mask" "F.Paste")
			(net "PV_VTT_DDR_A")
			(options
				(clearance outline)
				(anchor circle)
			)
			(primitives
				(gr_poly
					(pts
						(arc
							(start 0.508 -0.2921)
							(mid 0.478242 -0.363942)
							(end 0.4064 -0.3937)
						)
						(arc
							(start -0.4064 -0.3937)
							(mid -0.478242 -0.363942)
							(end -0.508 -0.2921)
						)
						(arc
							(start -0.508 0.2921)
							(mid -0.478242 0.363942)
							(end -0.4064 0.3937)
						)
						(arc
							(start 0.4064 0.3937)
							(mid 0.478242 0.363942)
							(end 0.508 0.2921)
						)
					)
					(width 0)
					(fill yes)
				)
			)
		)
		(pad "2" smd custom
			(at 0 0.6604)
			(size 0.19685 0.19685)
			(layers "F.Cu" "F.Mask" "F.Paste")
			(net "GND")
			(options
				(clearance outline)
				(anchor circle)
			)
			(primitives
				(gr_poly
					(pts
						(arc
							(start 0.508 -0.2921)
							(mid 0.478242 -0.363942)
							(end 0.4064 -0.3937)
						)
						(arc
							(start -0.4064 -0.3937)
							(mid -0.478242 -0.363942)
							(end -0.508 -0.2921)
						)
						(arc
							(start -0.508 0.2921)
							(mid -0.478242 0.363942)
							(end -0.4064 0.3937)
						)
						(arc
							(start 0.4064 0.3937)
							(mid 0.478242 0.363942)
							(end 0.508 0.2921)
						)
					)
					(width 0)
					(fill yes)
				)
			)
		)
	)
	(footprint ""
		(layer "F.Cu")
		(at 56.007 -36.83 -90)
		(property "Reference" "R101"
			(at 0 0 270)
			(layer "F.SilkS")
			(hide yes)
			(effects
				(font
					(size 1.27 1.27)
				)
			)
		)
		(property "Value" "33R2F-3-GP"
			(at 0.064008 -3.993896 270)
			(unlocked yes)
			(layer "F.Fab")
			(hide yes)
			(effects
				(font
					(size 1.016 1.016)
					(thickness 0.1524)
				)
			)
		)
		(property "Device Type" "R402H16"
			(at 0.064008 -5.517896 270)
			(unlocked yes)
			(layer "F.Fab")
			(hide yes)
			(effects
				(font
					(size 1.016 1.016)
					(thickness 0.1524)
				)
			)
		)
		(duplicate_pad_numbers_are_jumpers no)
		(fp_rect
			(start -0.381 0.8382)
			(end 0.381 -0.8382)
			(stroke
				(width 0)
				(type default)
			)
			(fill no)
			(layer "F.CrtYd")
		)
		(fp_rect
			(start -0.381 0.8382)
			(end 0.381 -0.8382)
			(stroke
				(width 0)
				(type default)
			)
			(fill no)
			(layer "F.Fab")
		)
		(pad "1" smd custom
			(at 0 -0.4318 270)
			(size 0.127 0.127)
			(layers "F.Cu" "F.Mask" "F.Paste")
			(net "SPI_CPU_CS0#")
			(options
				(clearance outline)
				(anchor circle)
			)
			(primitives
				(gr_poly
					(pts
						(arc
							(start -0.2032 -0.2794)
							(mid -0.239121 -0.264521)
							(end -0.254 -0.2286)
						)
						(arc
							(start -0.254 0.2286)
							(mid -0.239121 0.264521)
							(end -0.2032 0.2794)
						)
						(arc
							(start 0.2032 0.2794)
							(mid 0.239121 0.264521)
							(end 0.254 0.2286)
						)
						(arc
							(start 0.254 -0.2286)
							(mid 0.239121 -0.264521)
							(end 0.2032 -0.2794)
						)
					)
					(width 0)
					(fill yes)
				)
			)
		)
		(pad "2" smd custom
			(at 0 0.4318 270)
			(size 0.127 0.127)
			(layers "F.Cu" "F.Mask" "F.Paste")
			(net "SPI_CS0_N_M_1")
			(options
				(clearance outline)
				(anchor circle)
			)
			(primitives
				(gr_poly
					(pts
						(arc
							(start -0.2032 -0.2794)
							(mid -0.239121 -0.264521)
							(end -0.254 -0.2286)
						)
						(arc
							(start -0.254 0.2286)
							(mid -0.239121 0.264521)
							(end -0.2032 0.2794)
						)
						(arc
							(start 0.2032 0.2794)
							(mid 0.239121 0.264521)
							(end 0.254 0.2286)
						)
						(arc
							(start 0.254 -0.2286)
							(mid 0.239121 -0.264521)
							(end 0.2032 -0.2794)
						)
					)
					(width 0)
					(fill yes)
				)
			)
		)
	)
	(footprint ""
		(layer "F.Cu")
		(at 71.374 -40.005)
		(property "Reference" "X1"
			(at 0 0 0)
			(layer "F.SilkS")
			(hide yes)
			(effects
				(font
					(size 1.27 1.27)
				)
			)
		)
		(property "Value" "X-32D768KHZ-56GP"
			(at 0 -5.0292 0)
			(unlocked yes)
			(layer "F.Fab")
			(hide yes)
			(effects
				(font
					(size 1.016 1.016)
					(thickness 0.1524)
				)
			)
		)
		(property "Device Type" "DST310SH34"
			(at 0 -6.5532 0)
			(unlocked yes)
			(layer "F.Fab")
			(hide yes)
			(effects
				(font
					(size 1.016 1.016)
					(thickness 0.1524)
				)
			)
		)
		(duplicate_pad_numbers_are_jumpers no)
		(fp_rect
			(start -1.0033 1.9939)
			(end 1.0033 -1.9939)
			(stroke
				(width 0)
				(type default)
			)
			(fill no)
			(layer "F.CrtYd")
		)
		(fp_rect
			(start -1.0033 1.9939)
			(end 1.0033 -1.9939)
			(stroke
				(width 0)
				(type default)
			)
			(fill no)
			(layer "F.Fab")
		)
		(pad "1" smd rect
			(at 0 -1.230884)
			(size 1.7526 1.27)
			(layers "F.Cu" "F.Mask" "F.Paste")
			(net "RTC_X1PAD")
		)
		(pad "2" smd rect
			(at 0 1.230884)
			(size 1.7526 1.27)
			(layers "F.Cu" "F.Mask" "F.Paste")
			(net "RTC_X2PAD")
		)
	)
	(footprint ""
		(layer "F.Cu")
		(at 42.5196 -39.1414)
		(property "Reference" "C22"
			(at 0 0 0)
			(layer "F.SilkS")
			(hide yes)
			(effects
				(font
					(size 1.27 1.27)
				)
			)
		)
		(property "Value" "SC1U10V2KX-1GP"
			(at 1.8923 -1.2065 0)
			(unlocked yes)
			(layer "F.Fab")
			(hide yes)
			(effects
				(font
					(size 1.016 1.016)
					(thickness 0.1524)
				)
			)
		)
		(property "Device Type" "C402H22"
			(at 1.8923 -2.7305 0)
			(unlocked yes)
			(layer "F.Fab")
			(hide yes)
			(effects
				(font
					(size 1.016 1.016)
					(thickness 0.1524)
				)
			)
		)
		(duplicate_pad_numbers_are_jumpers no)
		(fp_rect
			(start -0.381 0.7366)
			(end 0.381 -0.7366)
			(stroke
				(width 0)
				(type default)
			)
			(fill no)
			(layer "F.CrtYd")
		)
		(fp_rect
			(start -0.381 0.7366)
			(end 0.381 -0.7366)
			(stroke
				(width 0)
				(type default)
			)
			(fill no)
			(layer "F.Fab")
		)
		(pad "1" smd custom
			(at 0 -0.4572)
			(size 0.1143 0.1143)
			(layers "F.Cu" "F.Mask" "F.Paste")
			(net "CLK_GEN_DELAY0_PG")
			(options
				(clearance outline)
				(anchor circle)
			)
			(primitives
				(gr_poly
					(pts
						(arc
							(start -0.254 -0.1778)
							(mid -0.239121 -0.213721)
							(end -0.2032 -0.2286)
						)
						(arc
							(start 0.2032 -0.2286)
							(mid 0.239121 -0.213721)
							(end 0.254 -0.1778)
						)
						(arc
							(start 0.254 0.1778)
							(mid 0.239121 0.213721)
							(end 0.2032 0.2286)
						)
						(arc
							(start -0.2032 0.2286)
							(mid -0.239121 0.213721)
							(end -0.254 0.1778)
						)
					)
					(width 0)
					(fill yes)
				)
			)
		)
		(pad "2" smd custom
			(at 0 0.4572)
			(size 0.1143 0.1143)
			(layers "F.Cu" "F.Mask" "F.Paste")
			(net "GND")
			(options
				(clearance outline)
				(anchor circle)
			)
			(primitives
				(gr_poly
					(pts
						(arc
							(start -0.254 -0.1778)
							(mid -0.239121 -0.213721)
							(end -0.2032 -0.2286)
						)
						(arc
							(start 0.2032 -0.2286)
							(mid 0.239121 -0.213721)
							(end 0.254 -0.1778)
						)
						(arc
							(start 0.254 0.1778)
							(mid 0.239121 0.213721)
							(end 0.2032 0.2286)
						)
						(arc
							(start -0.2032 0.2286)
							(mid -0.239121 0.213721)
							(end -0.254 0.1778)
						)
					)
					(width 0)
					(fill yes)
				)
			)
		)
	)
	(footprint ""
		(layer "F.Cu")
		(at 8.4328 -28.7274 180)
		(property "Reference" "PC85"
			(at 0 0 180)
			(layer "F.SilkS")
			(hide yes)
			(effects
				(font
					(size 1.27 1.27)
				)
			)
		)
		(property "Value" "SC22U25V5MX-GP"
			(at 0 -4.9022 180)
			(unlocked yes)
			(layer "F.Fab")
			(hide yes)
			(effects
				(font
					(size 1.016 1.016)
					(thickness 0.1524)
				)
			)
		)
		(property "Device Type" "C805H58"
			(at 0 -6.8072 180)
			(unlocked yes)
			(layer "F.Fab")
			(hide yes)
			(effects
				(font
					(size 1.016 1.016)
					(thickness 0.1524)
				)
			)
		)
		(duplicate_pad_numbers_are_jumpers no)
		(fp_line
			(start 0.6096 0)
			(end -0.6096 0)
			(stroke
				(width 0.3048)
				(type default)
			)
			(layer "F.SilkS")
		)
		(fp_poly
			(pts
				(xy -0.9017 1.4351) (xy 0.9017 1.4351) (xy 0.9017 -1.4351) (xy -0.9017 -1.4351)
			)
			(stroke
				(width 0)
				(type default)
			)
			(fill no)
			(layer "F.CrtYd")
		)
		(fp_poly
			(pts
				(xy 0.9017 1.4351) (xy 0.9017 -1.4351) (xy -0.9017 -1.4351) (xy -0.9017 1.4351)
			)
			(stroke
				(width 0)
				(type default)
			)
			(fill no)
			(layer "F.Fab")
		)
		(pad "1" smd rect
			(at 0 -0.8382 180)
			(size 1.5494 0.9398)
			(layers "F.Cu" "F.Mask" "F.Paste")
			(net "P1V0_VIN")
		)
		(pad "2" smd rect
			(at 0 0.8382 180)
			(size 1.5494 0.9398)
			(layers "F.Cu" "F.Mask" "F.Paste")
			(net "GND")
		)
	)
	(footprint ""
		(layer "F.Cu")
		(at 129.921 -43.561 180)
		(property "Reference" "C134"
			(at 0 0 180)
			(layer "F.SilkS")
			(hide yes)
			(effects
				(font
					(size 1.27 1.27)
				)
			)
		)
		(property "Value" "SCD1U10V2KX-5GP"
			(at 1.1811 -2.7051 180)
			(unlocked yes)
			(layer "F.Fab")
			(hide yes)
			(effects
				(font
					(size 1.016 1.016)
					(thickness 0.1524)
				)
			)
		)
		(property "Device Type" "C402H22"
			(at 1.1811 -4.2291 180)
			(unlocked yes)
			(layer "F.Fab")
			(hide yes)
			(effects
				(font
					(size 1.016 1.016)
					(thickness 0.1524)
				)
			)
		)
		(duplicate_pad_numbers_are_jumpers no)
		(fp_rect
			(start -0.381 0.7366)
			(end 0.381 -0.7366)
			(stroke
				(width 0)
				(type default)
			)
			(fill no)
			(layer "F.CrtYd")
		)
		(fp_rect
			(start -0.381 0.7366)
			(end 0.381 -0.7366)
			(stroke
				(width 0)
				(type default)
			)
			(fill no)
			(layer "F.Fab")
		)
		(pad "1" smd custom
			(at 0 -0.4572 180)
			(size 0.1143 0.1143)
			(layers "F.Cu" "F.Mask" "F.Paste")
			(net "P3V3_STBY")
			(options
				(clearance outline)
				(anchor circle)
			)
			(primitives
				(gr_poly
					(pts
						(arc
							(start -0.254 -0.1778)
							(mid -0.239121 -0.213721)
							(end -0.2032 -0.2286)
						)
						(arc
							(start 0.2032 -0.2286)
							(mid 0.239121 -0.213721)
							(end 0.254 -0.1778)
						)
						(arc
							(start 0.254 0.1778)
							(mid 0.239121 0.213721)
							(end 0.2032 0.2286)
						)
						(arc
							(start -0.2032 0.2286)
							(mid -0.239121 0.213721)
							(end -0.254 0.1778)
						)
					)
					(width 0)
					(fill yes)
				)
			)
		)
		(pad "2" smd custom
			(at 0 0.4572 180)
			(size 0.1143 0.1143)
			(layers "F.Cu" "F.Mask" "F.Paste")
			(net "GND")
			(options
				(clearance outline)
				(anchor circle)
			)
			(primitives
				(gr_poly
					(pts
						(arc
							(start -0.254 -0.1778)
							(mid -0.239121 -0.213721)
							(end -0.2032 -0.2286)
						)
						(arc
							(start 0.2032 -0.2286)
							(mid 0.239121 -0.213721)
							(end 0.254 -0.1778)
						)
						(arc
							(start 0.254 0.1778)
							(mid 0.239121 0.213721)
							(end 0.2032 0.2286)
						)
						(arc
							(start -0.2032 0.2286)
							(mid -0.239121 0.213721)
							(end -0.254 0.1778)
						)
					)
					(width 0)
					(fill yes)
				)
			)
		)
	)
	(footprint ""
		(layer "F.Cu")
		(at 201.3458 -45.974 180)
		(property "Reference" "PL2"
			(at 0 0 180)
			(layer "F.SilkS")
			(hide yes)
			(effects
				(font
					(size 1.27 1.27)
				)
			)
		)
		(property "Value" "IND-300NH-8-GP"
			(at -4.9403 -2.921 180)
			(unlocked yes)
			(layer "F.Fab")
			(hide yes)
			(effects
				(font
					(size 1.016 1.016)
					(thickness 0.1524)
				)
			)
		)
		(property "Device Type" "L102078-254224H296"
			(at -4.9403 -4.445 180)
			(unlocked yes)
			(layer "F.Fab")
			(hide yes)
			(effects
				(font
					(size 1.016 1.016)
					(thickness 0.1524)
				)
			)
		)
		(duplicate_pad_numbers_are_jumpers no)
		(fp_rect
			(start -4.1529 5.6134)
			(end 4.1529 -5.6134)
			(stroke
				(width 0)
				(type default)
			)
			(fill no)
			(layer "F.CrtYd")
		)
		(fp_rect
			(start -4.1529 5.6134)
			(end 4.1529 -5.6134)
			(stroke
				(width 0)
				(type default)
			)
			(fill no)
			(layer "F.Fab")
		)
		(pad "1" smd rect
			(at 0 -3.893566 180)
			(size 2.4892 3.175)
			(layers "F.Cu" "F.Mask" "F.Paste")
			(net "VR_PVDDR_A_VSW")
		)
		(pad "2" smd rect
			(at 0 3.893566 180)
			(size 2.4892 3.175)
			(layers "F.Cu" "F.Mask" "F.Paste")
			(net "PV_VDDR")
		)
	)
)
